# T6G (Grand Teton) — schematic netlist excerpt (pin names and nets, part order shuffled) for the footprints in the layout excerpt that follows; sources: Cadence DE-HDL packaged netlist, KiCad conversion of 04192023_DAF0TMB3IC0_F0TG_MB_C_brd_V02_OCP.brd

R1073  Q_RES  4.7K 5% EMPTY  pkg 0201LF  page 298 : A = P1V8_CPU0_RT_1D ; B = TEST0_RT_CPU0_P2
PC8004  Q_CAP  22UF 16V 20% X6S  pkg C0805  page 208 : A = SW_P12V_AUX_PVDD11_S3_P0_FLT ; B = GND
R78  Q_RES  4.7K 5% EMPTY  pkg 0402LF  page 160 : A = P3V3 ; B = PU_U5_EN
PC105_1  Q_CAP  22UF 4V 20% X6S  pkg C0805  page 201 : A = PVDDCR_CPU1_P0 ; B = GND

(kicad_pcb
	(version 20260206)
	(generator "pcbnew")
	(generator_version "10.0")
	(general
		(thickness 1.6)
		(legacy_teardrops no)
	)
	(paper "A4")
	(title_block
		(title "04192023_DAF0TMB3IC0_F0TG_MB_C_brd_V02_OCP.brd")
		(comment 1 "Grand Teton / footprints 5433-5436 of 8354")
	)
	(layers
		(0 "F.Cu" signal "TOP")
		(4 "In1.Cu" signal "GND")
		(6 "In2.Cu" signal "IN1")
		(8 "In3.Cu" signal "GND1")
		(10 "In4.Cu" signal "IN2")
		(12 "In5.Cu" signal "GND2")
		(14 "In6.Cu" signal "IN3")
		(16 "In7.Cu" signal "GND3")
		(18 "In8.Cu" signal "VCC")
		(20 "In9.Cu" signal "VCC1")
		(22 "In10.Cu" signal "GND4")
		(24 "In11.Cu" signal "IN4")
		(26 "In12.Cu" signal "GND5")
		(28 "In13.Cu" signal "IN5")
		(30 "In14.Cu" signal "GND6")
		(32 "In15.Cu" signal "IN6")
		(34 "In16.Cu" signal "GND7")
		(2 "B.Cu" signal "BOTTOM")
		(9 "F.Adhes" user "F.Adhesive")
		(11 "B.Adhes" user "B.Adhesive")
		(13 "F.Paste" user "Package Geometry/Pastemask Top")
		(15 "B.Paste" user "Package Geometry/Pastemask Bottom")
		(5 "F.SilkS" user "Ref Des/Silkscreen Top")
		(7 "B.SilkS" user "Ref Des/Silkscreen Bottom")
		(1 "F.Mask" user "Board Geometry/Soldermask Top")
		(3 "B.Mask" user "Board Geometry/Soldermask Bottom")
		(17 "Dwgs.User" user "User.Drawings")
		(19 "Cmts.User" user "User.Comments")
		(21 "Eco1.User" user "User.Eco1")
		(23 "Eco2.User" user "User.Eco2")
		(25 "Edge.Cuts" user "Board Geometry/Outline")
		(27 "Margin" user)
		(31 "F.CrtYd" user "Package Geometry/Place Bound Top")
		(29 "B.CrtYd" user "Package Geometry/Place Bound Bottom")
		(35 "F.Fab" user "Ref Des/Assembly Top")
		(33 "B.Fab" user "Ref Des/Assembly Bottom")
	)
	(footprint ""
		(layer "B.Cu")
		(at 439.42 -356.235 180)
		(property "Reference" "PC8004"
			(at 0 0 0)
			(layer "B.SilkS")
			(hide yes)
			(effects
				(font
					(size 1.27 1.27)
				)
				(justify mirror)
			)
		)
		(property "Value" ""
			(at 0 0 0)
			(layer "B.Fab")
			(effects
				(font
					(size 1.27 1.27)
				)
				(justify mirror)
			)
		)
		(duplicate_pad_numbers_are_jumpers no)
		(fp_line
			(start 1.524 0.762)
			(end 1.524 -0.762)
			(stroke
				(width 0.1524)
				(type default)
			)
			(layer "B.SilkS")
		)
		(fp_line
			(start 1.524 -0.762)
			(end -1.524 -0.762)
			(stroke
				(width 0.1524)
				(type default)
			)
			(layer "B.SilkS")
		)
		(fp_line
			(start -1.524 0.762)
			(end 1.524 0.762)
			(stroke
				(width 0.1524)
				(type default)
			)
			(layer "B.SilkS")
		)
		(fp_line
			(start -1.524 -0.762)
			(end -1.524 0.762)
			(stroke
				(width 0.1524)
				(type default)
			)
			(layer "B.SilkS")
		)
		(fp_line
			(start 1.1049 0.724916)
			(end -1.1049 0.724916)
			(stroke
				(width 0.1)
				(type default)
			)
			(layer "B.Fab")
		)
		(fp_line
			(start 1.1049 -0.724916)
			(end 1.1049 0.724916)
			(stroke
				(width 0.1)
				(type default)
			)
			(layer "B.Fab")
		)
		(fp_line
			(start -1.1049 0.724916)
			(end -1.1049 -0.724916)
			(stroke
				(width 0.1)
				(type default)
			)
			(layer "B.Fab")
		)
		(fp_line
			(start -1.1049 -0.724916)
			(end 1.1049 -0.724916)
			(stroke
				(width 0.1)
				(type default)
			)
			(layer "B.Fab")
		)
		(pad "1" smd rect
			(at 0.889 0 180)
			(size 1.016 1.27)
			(layers "B.Cu" "B.Mask" "B.Paste")
			(net "SW_P12V_AUX_PVDD11_S3_P0_FLT")
		)
		(pad "2" smd rect
			(at -0.889 0 180)
			(size 1.016 1.27)
			(layers "B.Cu" "B.Mask" "B.Paste")
			(net "GND")
		)
	)
	(footprint ""
		(layer "B.Cu")
		(at 397.623538 -393.96416 180)
		(property "Reference" "R1073"
			(at 0 0 0)
			(layer "B.SilkS")
			(hide yes)
			(effects
				(font
					(size 1.27 1.27)
				)
				(justify mirror)
			)
		)
		(property "Value" ""
			(at 0 0 0)
			(layer "B.Fab")
			(effects
				(font
					(size 1.27 1.27)
				)
				(justify mirror)
			)
		)
		(duplicate_pad_numbers_are_jumpers no)
		(fp_line
			(start 0.32512 0.175006)
			(end 0.32512 -0.175006)
			(stroke
				(width 0.1)
				(type default)
			)
			(layer "B.Fab")
		)
		(fp_line
			(start 0.32512 -0.175006)
			(end -0.32512 -0.175006)
			(stroke
				(width 0.1)
				(type default)
			)
			(layer "B.Fab")
		)
		(fp_line
			(start -0.32512 0.175006)
			(end 0.32512 0.175006)
			(stroke
				(width 0.1)
				(type default)
			)
			(layer "B.Fab")
		)
		(fp_line
			(start -0.32512 -0.175006)
			(end -0.32512 0.175006)
			(stroke
				(width 0.1)
				(type default)
			)
			(layer "B.Fab")
		)
		(pad "1" smd rect
			(at 0.2667 0)
			(size 0.3048 0.381)
			(layers "B.Cu" "B.Mask" "B.Paste")
			(net "P1V8_CPU0_RT_1D")
		)
		(pad "2" smd rect
			(at -0.2667 0 180)
			(size 0.3048 0.381)
			(layers "B.Cu" "B.Mask" "B.Paste")
			(net "TEST0_RT_CPU0_P2")
		)
	)
	(footprint ""
		(layer "B.Cu")
		(at 240.792 -217.678 -90)
		(property "Reference" "R78"
			(at 0 0 90)
			(layer "B.SilkS")
			(hide yes)
			(effects
				(font
					(size 1.27 1.27)
				)
				(justify mirror)
			)
		)
		(property "Value" ""
			(at 0 0 90)
			(layer "B.Fab")
			(effects
				(font
					(size 1.27 1.27)
				)
				(justify mirror)
			)
		)
		(duplicate_pad_numbers_are_jumpers no)
		(fp_line
			(start -0.7874 0.4064)
			(end 0.7874 0.4064)
			(stroke
				(width 0.1524)
				(type default)
			)
			(layer "B.SilkS")
		)
		(fp_line
			(start 0.7874 0.4064)
			(end 0.7874 -0.4064)
			(stroke
				(width 0.1524)
				(type default)
			)
			(layer "B.SilkS")
		)
		(fp_line
			(start -0.7874 -0.4064)
			(end -0.7874 0.4064)
			(stroke
				(width 0.1524)
				(type default)
			)
			(layer "B.SilkS")
		)
		(fp_line
			(start 0.7874 -0.4064)
			(end -0.7874 -0.4064)
			(stroke
				(width 0.1524)
				(type default)
			)
			(layer "B.SilkS")
		)
		(fp_line
			(start -0.67945 0.3048)
			(end -0.120396 0.3048)
			(stroke
				(width 0.1)
				(type default)
			)
			(layer "B.Fab")
		)
		(fp_line
			(start -0.120396 0.3048)
			(end -0.120396 0.2794)
			(stroke
				(width 0.1)
				(type default)
			)
			(layer "B.Fab")
		)
		(fp_line
			(start 0.12065 0.3048)
			(end 0.67945 0.3048)
			(stroke
				(width 0.1)
				(type default)
			)
			(layer "B.Fab")
		)
		(fp_line
			(start 0.67945 0.3048)
			(end 0.67945 -0.305054)
			(stroke
				(width 0.1)
				(type default)
			)
			(layer "B.Fab")
		)
		(fp_line
			(start -0.120396 0.2794)
			(end 0.12065 0.2794)
			(stroke
				(width 0.1)
				(type default)
			)
			(layer "B.Fab")
		)
		(fp_line
			(start 0.12065 0.2794)
			(end 0.12065 0.3048)
			(stroke
				(width 0.1)
				(type default)
			)
			(layer "B.Fab")
		)
		(fp_line
			(start -0.12065 -0.2794)
			(end -0.12065 -0.3048)
			(stroke
				(width 0.1)
				(type default)
			)
			(layer "B.Fab")
		)
		(fp_line
			(start 0.12065 -0.2794)
			(end -0.12065 -0.2794)
			(stroke
				(width 0.1)
				(type default)
			)
			(layer "B.Fab")
		)
		(fp_line
			(start -0.67945 -0.3048)
			(end -0.67945 0.3048)
			(stroke
				(width 0.1)
				(type default)
			)
			(layer "B.Fab")
		)
		(fp_line
			(start -0.12065 -0.3048)
			(end -0.67945 -0.3048)
			(stroke
				(width 0.1)
				(type default)
			)
			(layer "B.Fab")
		)
		(fp_line
			(start 0.12065 -0.305054)
			(end 0.12065 -0.2794)
			(stroke
				(width 0.1)
				(type default)
			)
			(layer "B.Fab")
		)
		(fp_line
			(start 0.67945 -0.305054)
			(end 0.12065 -0.305054)
			(stroke
				(width 0.1)
				(type default)
			)
			(layer "B.Fab")
		)
		(pad "1" smd circle
			(at 0.40005 0 90)
			(size 0 0)
			(layers "B.Cu" "B.Mask" "B.Paste")
			(net "P3V3")
		)
		(pad "2" smd circle
			(at -0.40005 0 90)
			(size 0 0)
			(layers "B.Cu" "B.Mask" "B.Paste")
			(net "PU_U5_EN")
		)
	)
	(footprint ""
		(layer "B.Cu")
		(at 331.20584 -326.311006 -90)
		(property "Reference" "PC105_1"
			(at 0 0 90)
			(layer "B.SilkS")
			(hide yes)
			(effects
				(font
					(size 1.27 1.27)
				)
				(justify mirror)
			)
		)
		(property "Value" ""
			(at 0 0 90)
			(layer "B.Fab")
			(effects
				(font
					(size 1.27 1.27)
				)
				(justify mirror)
			)
		)
		(duplicate_pad_numbers_are_jumpers no)
		(fp_line
			(start -1.524 0.762)
			(end 1.524 0.762)
			(stroke
				(width 0.1524)
				(type default)
			)
			(layer "B.SilkS")
		)
		(fp_line
			(start 1.524 0.762)
			(end 1.524 -0.762)
			(stroke
				(width 0.1524)
				(type default)
			)
			(layer "B.SilkS")
		)
		(fp_line
			(start -1.524 -0.762)
			(end -1.524 0.762)
			(stroke
				(width 0.1524)
				(type default)
			)
			(layer "B.SilkS")
		)
		(fp_line
			(start 1.524 -0.762)
			(end -1.524 -0.762)
			(stroke
				(width 0.1524)
				(type default)
			)
			(layer "B.SilkS")
		)
		(fp_line
			(start -1.1049 0.724916)
			(end -1.1049 -0.724916)
			(stroke
				(width 0.1)
				(type default)
			)
			(layer "B.Fab")
		)
		(fp_line
			(start 1.1049 0.724916)
			(end -1.1049 0.724916)
			(stroke
				(width 0.1)
				(type default)
			)
			(layer "B.Fab")
		)
		(fp_line
			(start -1.1049 -0.724916)
			(end 1.1049 -0.724916)
			(stroke
				(width 0.1)
				(type default)
			)
			(layer "B.Fab")
		)
		(fp_line
			(start 1.1049 -0.724916)
			(end 1.1049 0.724916)
			(stroke
				(width 0.1)
				(type default)
			)
			(layer "B.Fab")
		)
		(pad "1" smd rect
			(at 0.889 0 270)
			(size 1.016 1.27)
			(layers "B.Cu" "B.Mask" "B.Paste")
			(net "PVDDCR_CPU1_P0")
		)
		(pad "2" smd rect
			(at -0.889 0 270)
			(size 1.016 1.27)
			(layers "B.Cu" "B.Mask" "B.Paste")
			(net "GND")
		)
	)
)
